(kicad_pcb
	(version 20260206)
	(generator "pcbnew")
	(generator_version "10.0")
	(general
		(thickness 1.6)
		(legacy_teardrops no)
	)
	(paper "A4")
	(title_block
		(title "Wiwynn_Tioga_Pass_MB.brd")
		(comment 1 "Tioga Pass / footprints 2616-2622 of 4770")
	)
	(layers
		(0 "F.Cu" signal "TOP")
		(4 "In1.Cu" signal "L2GND")
		(6 "In2.Cu" signal "L3")
		(8 "In3.Cu" signal "L4GND")
		(10 "In4.Cu" signal "L5")
		(12 "In5.Cu" signal "L6GND")
		(14 "In6.Cu" signal "L7VCC")
		(16 "In7.Cu" signal "L8VCC")
		(18 "In8.Cu" signal "L9GND")
		(20 "In9.Cu" signal "L10")
		(22 "In10.Cu" signal "L11GND")
		(24 "In11.Cu" signal "L12")
		(26 "In12.Cu" signal "L13GND")
		(2 "B.Cu" signal "BOTTOM")
		(9 "F.Adhes" user "F.Adhesive")
		(11 "B.Adhes" user "B.Adhesive")
		(13 "F.Paste" user "Package Geometry/Pastemask Top")
		(15 "B.Paste" user "Package Geometry/Pastemask Bottom")
		(5 "F.SilkS" user "Ref Des/Silkscreen Top")
		(7 "B.SilkS" user "Ref Des/Silkscreen Bottom")
		(1 "F.Mask" user "Board Geometry/Soldermask Top")
		(3 "B.Mask" user "Board Geometry/Soldermask Bottom")
		(17 "Dwgs.User" user "User.Drawings")
		(19 "Cmts.User" user "User.Comments")
		(21 "Eco1.User" user "User.Eco1")
		(23 "Eco2.User" user "User.Eco2")
		(25 "Edge.Cuts" user "Board Geometry/Outline")
		(27 "Margin" user)
		(31 "F.CrtYd" user "Package Geometry/Place Bound Top")
		(29 "B.CrtYd" user "Package Geometry/Place Bound Bottom")
		(35 "F.Fab" user "Ref Des/Assembly Top")
		(33 "B.Fab" user "Ref Des/Assembly Bottom")
	)
	(footprint ""
		(layer "B.Cu")
		(at 409.321 -20.828 -90)
		(property "Reference" "R1U28"
			(at 0 0 90)
			(layer "B.SilkS")
			(hide yes)
			(effects
				(font
					(size 1.27 1.27)
				)
				(justify mirror)
			)
		)
		(property "Value" "*"
			(at -0.064008 -4.108196 270)
			(unlocked yes)
			(layer "B.Fab")
			(hide yes)
			(effects
				(font
					(size 1.27 1.016)
					(thickness 0.1524)
				)
				(justify mirror)
			)
		)
		(property "Device Type" "1K82R2F-1-GP_SMD-RG-1K82R2F-1-A"
			(at -0.064008 -5.632196 270)
			(unlocked yes)
			(layer "B.Fab")
			(hide yes)
			(effects
				(font
					(size 1.27 1.016)
					(thickness 0.1524)
				)
				(justify mirror)
			)
		)
		(duplicate_pad_numbers_are_jumpers no)
		(fp_line
			(start -0.508 -0.9398)
			(end 0.508 -0.9398)
			(stroke
				(width 0.1524)
				(type default)
			)
			(layer "B.SilkS")
		)
		(fp_line
			(start 0.508 -0.9398)
			(end 0.508 0.9398)
			(stroke
				(width 0.1524)
				(type default)
			)
			(layer "B.SilkS")
		)
		(fp_rect
			(start 0.508 0.9398)
			(end -0.508 -0.9398)
			(stroke
				(width 0)
				(type default)
			)
			(fill no)
			(layer "B.CrtYd")
		)
		(fp_rect
			(start 0.508 0.9398)
			(end -0.508 -0.9398)
			(stroke
				(width 0)
				(type default)
			)
			(fill no)
			(layer "B.Fab")
		)
		(pad "1" smd custom
			(at 0 -0.4445 90)
			(size 0.1397 0.1397)
			(layers "B.Cu" "B.Mask" "B.Paste")
			(net "A_P5V_SCALED")
			(options
				(clearance outline)
				(anchor circle)
			)
			(primitives
				(gr_poly
					(pts
						(arc
							(start -0.1778 0.2794)
							(mid -0.249642 0.249642)
							(end -0.2794 0.1778)
						)
						(arc
							(start -0.2794 -0.1778)
							(mid -0.249642 -0.249642)
							(end -0.1778 -0.2794)
						)
						(arc
							(start 0.1778 -0.2794)
							(mid 0.249642 -0.249642)
							(end 0.2794 -0.1778)
						)
						(arc
							(start 0.2794 0.1778)
							(mid 0.249642 0.249642)
							(end 0.1778 0.2794)
						)
					)
					(width 0)
					(fill yes)
				)
			)
		)
		(pad "2" smd custom
			(at 0 0.4445 90)
			(size 0.1397 0.1397)
			(layers "B.Cu" "B.Mask" "B.Paste")
			(net "GND")
			(options
				(clearance outline)
				(anchor circle)
			)
			(primitives
				(gr_poly
					(pts
						(arc
							(start -0.1778 0.2794)
							(mid -0.249642 0.249642)
							(end -0.2794 0.1778)
						)
						(arc
							(start -0.2794 -0.1778)
							(mid -0.249642 -0.249642)
							(end -0.1778 -0.2794)
						)
						(arc
							(start 0.1778 -0.2794)
							(mid 0.249642 -0.249642)
							(end 0.2794 -0.1778)
						)
						(arc
							(start 0.2794 0.1778)
							(mid 0.249642 0.249642)
							(end 0.1778 0.2794)
						)
					)
					(width 0)
					(fill yes)
				)
			)
		)
	)
	(footprint ""
		(layer "B.Cu")
		(at 368.716814 -125.507242 -90)
		(property "Reference" "C3M35"
			(at 0 0 90)
			(layer "B.SilkS")
			(hide yes)
			(effects
				(font
					(size 1.27 1.27)
				)
				(justify mirror)
			)
		)
		(property "Value" ""
			(at 0 0 90)
			(layer "B.Fab")
			(effects
				(font
					(size 1.27 1.27)
				)
				(justify mirror)
			)
		)
		(duplicate_pad_numbers_are_jumpers no)
		(fp_poly
			(pts
				(xy -0.3048 -0.1016) (xy -0.3048 0.9906) (xy 0.3048 0.9906) (xy 0.3048 -0.1016)
			)
			(stroke
				(width 0)
				(type default)
			)
			(fill no)
			(layer "B.CrtYd")
		)
		(fp_line
			(start -0.3048 0.9906)
			(end -0.3048 -0.1016)
			(stroke
				(width 0.1)
				(type default)
			)
			(layer "B.Fab")
		)
		(fp_line
			(start 0.3048 0.9906)
			(end -0.3048 0.9906)
			(stroke
				(width 0.1)
				(type default)
			)
			(layer "B.Fab")
		)
		(fp_line
			(start -0.3048 -0.1016)
			(end 0.3048 -0.1016)
			(stroke
				(width 0.1)
				(type default)
			)
			(layer "B.Fab")
		)
		(fp_line
			(start 0.3048 -0.1016)
			(end 0.3048 0.9906)
			(stroke
				(width 0.1)
				(type default)
			)
			(layer "B.Fab")
		)
		(pad "1" smd rect
			(at 0 0 90)
			(size 0.508 0.508)
			(layers "B.Cu" "B.Mask" "B.Paste")
			(net "P3E_CPU0_PE1_PCH_R_RXN<9>")
		)
		(pad "2" smd rect
			(at 0 0.889 90)
			(size 0.508 0.508)
			(layers "B.Cu" "B.Mask" "B.Paste")
			(net "P3E_CPU0_PE1_PCH_RXN<9>")
		)
		(zone
			(layer "B.Cu")
			(hatch none 0.5)
			(connect_pads
				(clearance 0)
			)
			(min_thickness 0.25)
			(keepout
				(tracks not_allowed)
				(vias allowed)
				(pads allowed)
				(copperpour not_allowed)
				(footprints allowed)
			)
			(placement
				(enabled no)
				(sheetname "")
			)
			(fill
				(thermal_gap 0.5)
				(thermal_bridge_width 0.5)
				(island_removal_mode 0)
			)
			(polygon
				(pts
					(xy 368.081814 -125.253242) (xy 368.081814 -125.761242) (xy 368.462814 -125.761242) (xy 368.462814 -125.253242)
				)
			)
		)
		(zone
			(layer "B.Cu")
			(hatch none 0.5)
			(connect_pads
				(clearance 0)
			)
			(min_thickness 0.25)
			(keepout
				(tracks allowed)
				(vias not_allowed)
				(pads allowed)
				(copperpour not_allowed)
				(footprints allowed)
			)
			(placement
				(enabled no)
				(sheetname "")
			)
			(fill
				(thermal_gap 0.5)
				(thermal_bridge_width 0.5)
				(island_removal_mode 0)
			)
			(polygon
				(pts
					(xy 368.462814 -125.253242) (xy 368.462814 -125.761242) (xy 368.081814 -125.761242) (xy 368.081814 -125.253242)
				)
			)
		)
	)
	(footprint ""
		(layer "B.Cu")
		(at 33.622996 -85.733382 90)
		(property "Reference" "C1C18"
			(at 0 0 90)
			(layer "B.SilkS")
			(hide yes)
			(effects
				(font
					(size 1.27 1.27)
				)
				(justify mirror)
			)
		)
		(property "Value" "*"
			(at -1.1811 -2.8194 90)
			(unlocked yes)
			(layer "B.Fab")
			(hide yes)
			(effects
				(font
					(size 1.27 1.016)
					(thickness 0.1524)
				)
				(justify mirror)
			)
		)
		(property "Device Type" "SC1U10V2KX-4-GP_SMD-BCG6-SC1U1A"
			(at -1.1811 -4.3434 90)
			(unlocked yes)
			(layer "B.Fab")
			(hide yes)
			(effects
				(font
					(size 1.27 1.016)
					(thickness 0.1524)
				)
				(justify mirror)
			)
		)
		(duplicate_pad_numbers_are_jumpers no)
		(fp_rect
			(start 0.4318 0.9525)
			(end -0.4318 -0.9525)
			(stroke
				(width 0)
				(type default)
			)
			(fill no)
			(layer "B.CrtYd")
		)
		(fp_rect
			(start 0.4318 0.9525)
			(end -0.4318 -0.9525)
			(stroke
				(width 0)
				(type default)
			)
			(fill no)
			(layer "B.Fab")
		)
		(pad "1" smd custom
			(at 0 -0.4445 270)
			(size 0.1524 0.1524)
			(layers "B.Cu" "B.Mask" "B.Paste")
			(net "P5V_STBY")
			(options
				(clearance outline)
				(anchor circle)
			)
			(primitives
				(gr_poly
					(pts
						(arc
							(start 0.3048 0.2032)
							(mid 0.275042 0.275042)
							(end 0.2032 0.3048)
						)
						(arc
							(start -0.2032 0.3048)
							(mid -0.275042 0.275042)
							(end -0.3048 0.2032)
						)
						(arc
							(start -0.3048 -0.2032)
							(mid -0.275042 -0.275042)
							(end -0.2032 -0.3048)
						)
						(arc
							(start 0.2032 -0.3048)
							(mid 0.275042 -0.275042)
							(end 0.3048 -0.2032)
						)
					)
					(width 0)
					(fill yes)
				)
			)
		)
		(pad "2" smd custom
			(at 0 0.4445 270)
			(size 0.1524 0.1524)
			(layers "B.Cu" "B.Mask" "B.Paste")
			(net "GND")
			(options
				(clearance outline)
				(anchor circle)
			)
			(primitives
				(gr_poly
					(pts
						(arc
							(start 0.3048 0.2032)
							(mid 0.275042 0.275042)
							(end 0.2032 0.3048)
						)
						(arc
							(start -0.2032 0.3048)
							(mid -0.275042 0.275042)
							(end -0.3048 0.2032)
						)
						(arc
							(start -0.3048 -0.2032)
							(mid -0.275042 -0.275042)
							(end -0.2032 -0.3048)
						)
						(arc
							(start 0.2032 -0.3048)
							(mid 0.275042 -0.275042)
							(end 0.3048 -0.2032)
						)
					)
					(width 0)
					(fill yes)
				)
			)
		)
	)
	(footprint ""
		(layer "B.Cu")
		(at 399.530824 -124.738384 90)
		(property "Reference" "C2M4"
			(at 0 0 90)
			(layer "B.SilkS")
			(hide yes)
			(effects
				(font
					(size 1.27 1.27)
				)
				(justify mirror)
			)
		)
		(property "Value" ""
			(at 0 0 90)
			(layer "B.Fab")
			(effects
				(font
					(size 1.27 1.27)
				)
				(justify mirror)
			)
		)
		(duplicate_pad_numbers_are_jumpers no)
		(fp_poly
			(pts
				(xy -0.3048 -0.1016) (xy -0.3048 0.9906) (xy 0.3048 0.9906) (xy 0.3048 -0.1016)
			)
			(stroke
				(width 0)
				(type default)
			)
			(fill no)
			(layer "B.CrtYd")
		)
		(fp_line
			(start 0.3048 -0.1016)
			(end 0.3048 0.9906)
			(stroke
				(width 0.1)
				(type default)
			)
			(layer "B.Fab")
		)
		(fp_line
			(start -0.3048 -0.1016)
			(end 0.3048 -0.1016)
			(stroke
				(width 0.1)
				(type default)
			)
			(layer "B.Fab")
		)
		(fp_line
			(start 0.3048 0.9906)
			(end -0.3048 0.9906)
			(stroke
				(width 0.1)
				(type default)
			)
			(layer "B.Fab")
		)
		(fp_line
			(start -0.3048 0.9906)
			(end -0.3048 -0.1016)
			(stroke
				(width 0.1)
				(type default)
			)
			(layer "B.Fab")
		)
		(pad "1" smd rect
			(at 0 0 270)
			(size 0.508 0.508)
			(layers "B.Cu" "B.Mask" "B.Paste")
			(net "P2E_SSB_BMC_TX_DP")
		)
		(pad "2" smd rect
			(at 0 0.889 270)
			(size 0.508 0.508)
			(layers "B.Cu" "B.Mask" "B.Paste")
			(net "P2E_SSB_BMC_TX_C_DP")
		)
		(zone
			(layer "B.Cu")
			(hatch none 0.5)
			(connect_pads
				(clearance 0)
			)
			(min_thickness 0.25)
			(keepout
				(tracks allowed)
				(vias not_allowed)
				(pads allowed)
				(copperpour not_allowed)
				(footprints allowed)
			)
			(placement
				(enabled no)
				(sheetname "")
			)
			(fill
				(thermal_gap 0.5)
				(thermal_bridge_width 0.5)
				(island_removal_mode 0)
			)
			(polygon
				(pts
					(xy 399.784824 -124.992384) (xy 399.784824 -124.484384) (xy 400.165824 -124.484384) (xy 400.165824 -124.992384)
				)
			)
		)
		(zone
			(layer "B.Cu")
			(hatch none 0.5)
			(connect_pads
				(clearance 0)
			)
			(min_thickness 0.25)
			(keepout
				(tracks not_allowed)
				(vias allowed)
				(pads allowed)
				(copperpour not_allowed)
				(footprints allowed)
			)
			(placement
				(enabled no)
				(sheetname "")
			)
			(fill
				(thermal_gap 0.5)
				(thermal_bridge_width 0.5)
				(island_removal_mode 0)
			)
			(polygon
				(pts
					(xy 400.165824 -124.992384) (xy 400.165824 -124.484384) (xy 399.784824 -124.484384) (xy 399.784824 -124.992384)
				)
			)
		)
	)
	(footprint ""
		(layer "B.Cu")
		(at 437.690006 -43.54195 180)
		(property "Reference" "R25W39"
			(at 0 0 0)
			(layer "B.SilkS")
			(hide yes)
			(effects
				(font
					(size 1.27 1.27)
				)
				(justify mirror)
			)
		)
		(property "Value" "*"
			(at -0.064008 -4.108196 180)
			(unlocked yes)
			(layer "B.Fab")
			(hide yes)
			(effects
				(font
					(size 1.27 1.016)
					(thickness 0.1524)
				)
				(justify mirror)
			)
		)
		(property "Device Type" "120R2F-GP_RCL_GP-120R2F-GP,64.A"
			(at -0.064008 -5.632196 180)
			(unlocked yes)
			(layer "B.Fab")
			(hide yes)
			(effects
				(font
					(size 1.27 1.016)
					(thickness 0.1524)
				)
				(justify mirror)
			)
		)
		(duplicate_pad_numbers_are_jumpers no)
		(fp_line
			(start 0.508 -0.9398)
			(end 0.508 0.9398)
			(stroke
				(width 0.1524)
				(type default)
			)
			(layer "B.SilkS")
		)
		(fp_line
			(start -0.508 -0.9398)
			(end 0.508 -0.9398)
			(stroke
				(width 0.1524)
				(type default)
			)
			(layer "B.SilkS")
		)
		(fp_rect
			(start 0.508 0.9398)
			(end -0.508 -0.9398)
			(stroke
				(width 0)
				(type default)
			)
			(fill no)
			(layer "B.CrtYd")
		)
		(fp_rect
			(start 0.508 0.9398)
			(end -0.508 -0.9398)
			(stroke
				(width 0)
				(type default)
			)
			(fill no)
			(layer "B.Fab")
		)
		(pad "1" smd custom
			(at 0 -0.4445)
			(size 0.1397 0.1397)
			(layers "B.Cu" "B.Mask" "B.Paste")
			(net "BMC_M_A1")
			(options
				(clearance outline)
				(anchor circle)
			)
			(primitives
				(gr_poly
					(pts
						(arc
							(start -0.1778 0.2794)
							(mid -0.249642 0.249642)
							(end -0.2794 0.1778)
						)
						(arc
							(start -0.2794 -0.1778)
							(mid -0.249642 -0.249642)
							(end -0.1778 -0.2794)
						)
						(arc
							(start 0.1778 -0.2794)
							(mid 0.249642 -0.249642)
							(end 0.2794 -0.1778)
						)
						(arc
							(start 0.2794 0.1778)
							(mid 0.249642 0.249642)
							(end 0.1778 0.2794)
						)
					)
					(width 0)
					(fill yes)
				)
			)
		)
		(pad "2" smd custom
			(at 0 0.4445)
			(size 0.1397 0.1397)
			(layers "B.Cu" "B.Mask" "B.Paste")
			(net "P1V2_AUX_BMC")
			(options
				(clearance outline)
				(anchor circle)
			)
			(primitives
				(gr_poly
					(pts
						(arc
							(start -0.1778 0.2794)
							(mid -0.249642 0.249642)
							(end -0.2794 0.1778)
						)
						(arc
							(start -0.2794 -0.1778)
							(mid -0.249642 -0.249642)
							(end -0.1778 -0.2794)
						)
						(arc
							(start 0.1778 -0.2794)
							(mid 0.249642 -0.249642)
							(end 0.2794 -0.1778)
						)
						(arc
							(start 0.2794 0.1778)
							(mid 0.249642 0.249642)
							(end 0.1778 0.2794)
						)
					)
					(width 0)
					(fill yes)
				)
			)
		)
	)
	(footprint ""
		(layer "B.Cu")
		(at 444.062866 -38.39591 90)
		(property "Reference" "R25W118"
			(at 0.8382 -0.67818 90)
			(unlocked yes)
			(layer "B.SilkS")
			(effects
				(font
					(size 0.4064 0.254)
					(thickness 0.1524)
				)
				(justify left mirror)
			)
		)
		(property "Value" ""
			(at 0 0 90)
			(layer "B.Fab")
			(effects
				(font
					(size 1.27 1.27)
				)
				(justify mirror)
			)
		)
		(duplicate_pad_numbers_are_jumpers no)
		(fp_poly
			(pts
				(xy 0.2794 -0.1016) (xy -0.2794 -0.1016) (xy -0.2794 0.9906) (xy 0.2794 0.9906)
			)
			(stroke
				(width 0)
				(type default)
			)
			(fill no)
			(layer "B.CrtYd")
		)
		(fp_line
			(start 0.2794 -0.1016)
			(end 0.2794 0.9906)
			(stroke
				(width 0.1)
				(type default)
			)
			(layer "B.Fab")
		)
		(fp_line
			(start -0.2794 -0.1016)
			(end 0.2794 -0.1016)
			(stroke
				(width 0.1)
				(type default)
			)
			(layer "B.Fab")
		)
		(fp_line
			(start 0.2794 0.9906)
			(end -0.2794 0.9906)
			(stroke
				(width 0.1)
				(type default)
			)
			(layer "B.Fab")
		)
		(fp_line
			(start -0.2794 0.9906)
			(end -0.2794 -0.1016)
			(stroke
				(width 0.1)
				(type default)
			)
			(layer "B.Fab")
		)
		(pad "1" smd rect
			(at 0 0 270)
			(size 0.508 0.508)
			(layers "B.Cu" "B.Mask" "B.Paste")
			(net "BMC_M_PAR")
		)
		(pad "2" smd rect
			(at 0 0.889 270)
			(size 0.508 0.508)
			(layers "B.Cu" "B.Mask" "B.Paste")
			(net "GND")
		)
		(zone
			(layer "B.Cu")
			(hatch none 0.5)
			(connect_pads
				(clearance 0)
			)
			(min_thickness 0.25)
			(keepout
				(tracks allowed)
				(vias not_allowed)
				(pads allowed)
				(copperpour not_allowed)
				(footprints allowed)
			)
			(placement
				(enabled no)
				(sheetname "")
			)
			(fill
				(thermal_gap 0.5)
				(thermal_bridge_width 0.5)
				(island_removal_mode 0)
			)
			(polygon
				(pts
					(xy 444.316866 -38.64991) (xy 444.316866 -38.14191) (xy 444.697866 -38.14191) (xy 444.697866 -38.64991)
				)
			)
		)
		(zone
			(layer "B.Cu")
			(hatch none 0.5)
			(connect_pads
				(clearance 0)
			)
			(min_thickness 0.25)
			(keepout
				(tracks not_allowed)
				(vias allowed)
				(pads allowed)
				(copperpour not_allowed)
				(footprints allowed)
			)
			(placement
				(enabled no)
				(sheetname "")
			)
			(fill
				(thermal_gap 0.5)
				(thermal_bridge_width 0.5)
				(island_removal_mode 0)
			)
			(polygon
				(pts
					(xy 444.697866 -38.64991) (xy 444.697866 -38.14191) (xy 444.316866 -38.14191) (xy 444.316866 -38.64991)
				)
			)
		)
	)
	(footprint ""
		(layer "B.Cu")
		(at 2.8702 -61.6712 -90)
		(property "Reference" "C9R5"
			(at 0 0 90)
			(layer "B.SilkS")
			(hide yes)
			(effects
				(font
					(size 1.27 1.27)
				)
				(justify mirror)
			)
		)
		(property "Value" ""
			(at 0 0 90)
			(layer "B.Fab")
			(effects
				(font
					(size 1.27 1.27)
				)
				(justify mirror)
			)
		)
		(duplicate_pad_numbers_are_jumpers no)
		(fp_rect
			(start -0.7239 -0.2159)
			(end 0.7239 1.9939)
			(stroke
				(width 0)
				(type default)
			)
			(fill no)
			(layer "B.CrtYd")
		)
		(fp_line
			(start -0.7239 1.9939)
			(end -0.7239 -0.2159)
			(stroke
				(width 0.1)
				(type default)
			)
			(layer "B.Fab")
		)
		(fp_line
			(start 0.7239 1.9939)
			(end -0.7239 1.9939)
			(stroke
				(width 0.1)
				(type default)
			)
			(layer "B.Fab")
		)
		(fp_line
			(start -0.7239 -0.2159)
			(end 0.7239 -0.2159)
			(stroke
				(width 0.1)
				(type default)
			)
			(layer "B.Fab")
		)
		(fp_line
			(start 0.7239 -0.2159)
			(end 0.7239 1.9939)
			(stroke
				(width 0.1)
				(type default)
			)
			(layer "B.Fab")
		)
		(pad "1" smd rect
			(at 0 0 90)
			(size 1.27 1.016)
			(layers "B.Cu" "B.Mask" "B.Paste")
			(net "P12V_PSU")
		)
		(pad "2" smd rect
			(at 0 1.778 90)
			(size 1.27 1.016)
			(layers "B.Cu" "B.Mask" "B.Paste")
			(net "GND")
		)
		(zone
			(layer "B.Cu")
			(hatch none 0.5)
			(connect_pads
				(clearance 0)
			)
			(min_thickness 0.25)
			(keepout
				(tracks not_allowed)
				(vias allowed)
				(pads allowed)
				(copperpour not_allowed)
				(footprints allowed)
			)
			(placement
				(enabled no)
				(sheetname "")
			)
			(fill
				(thermal_gap 0.5)
				(thermal_bridge_width 0.5)
				(island_removal_mode 0)
			)
			(polygon
				(pts
					(xy 2.3622 -62.3062) (xy 1.6002 -62.3062) (xy 1.6002 -61.0362) (xy 2.3622 -61.0362)
				)
			)
		)
	)
)
